(kicad_pcb
	(version 20260206)
	(generator "pcbnew")
	(generator_version "10.0")
	(general
		(thickness 1.6)
		(legacy_teardrops no)
	)
	(paper "A4")
	(title_block
		(title "12092022_DA0F0TFB6D0_F0T_FAN_BOARD_MP5048_D_brd_v02_OCP.brd")
		(comment 1 "Grand Teton / footprints 302-307 of 924")
	)
	(layers
		(0 "F.Cu" signal "TOP")
		(4 "In1.Cu" signal "GND")
		(6 "In2.Cu" signal "IN1")
		(8 "In3.Cu" signal "IN2")
		(10 "In4.Cu" signal "GND1")
		(2 "B.Cu" signal "BOTTOM")
		(9 "F.Adhes" user "F.Adhesive")
		(11 "B.Adhes" user "B.Adhesive")
		(13 "F.Paste" user "Package Geometry/Pastemask Top")
		(15 "B.Paste" user "Package Geometry/Pastemask Bottom")
		(5 "F.SilkS" user "Ref Des/Silkscreen Top")
		(7 "B.SilkS" user "Ref Des/Silkscreen Bottom")
		(1 "F.Mask" user "Board Geometry/Soldermask Top")
		(3 "B.Mask" user "Board Geometry/Soldermask Bottom")
		(17 "Dwgs.User" user "User.Drawings")
		(19 "Cmts.User" user "User.Comments")
		(21 "Eco1.User" user "User.Eco1")
		(23 "Eco2.User" user "User.Eco2")
		(25 "Edge.Cuts" user "Board Geometry/Outline")
		(27 "Margin" user)
		(31 "F.CrtYd" user "Package Geometry/Place Bound Top")
		(29 "B.CrtYd" user "Package Geometry/Place Bound Bottom")
		(35 "F.Fab" user "Ref Des/Assembly Top")
		(33 "B.Fab" user "Ref Des/Assembly Bottom")
	)
	(footprint ""
		(layer "F.Cu")
		(at 27.051 -127.508 -90)
		(property "Reference" "R4943"
			(at 0 0 270)
			(layer "F.SilkS")
			(hide yes)
			(effects
				(font
					(size 1.27 1.27)
				)
			)
		)
		(property "Value" ""
			(at 0 0 270)
			(layer "F.Fab")
			(effects
				(font
					(size 1.27 1.27)
				)
			)
		)
		(duplicate_pad_numbers_are_jumpers no)
		(fp_line
			(start -0.7874 0.4064)
			(end -0.7874 -0.4064)
			(stroke
				(width 0.1524)
				(type default)
			)
			(layer "F.SilkS")
		)
		(fp_line
			(start 0.7874 0.4064)
			(end -0.7874 0.4064)
			(stroke
				(width 0.1524)
				(type default)
			)
			(layer "F.SilkS")
		)
		(fp_line
			(start -0.7874 -0.4064)
			(end 0.7874 -0.4064)
			(stroke
				(width 0.1524)
				(type default)
			)
			(layer "F.SilkS")
		)
		(fp_line
			(start 0.7874 -0.4064)
			(end 0.7874 0.4064)
			(stroke
				(width 0.1524)
				(type default)
			)
			(layer "F.SilkS")
		)
		(fp_line
			(start -0.67945 0.3048)
			(end -0.67945 -0.305054)
			(stroke
				(width 0.1)
				(type default)
			)
			(layer "F.Fab")
		)
		(fp_line
			(start -0.12065 0.3048)
			(end -0.67945 0.3048)
			(stroke
				(width 0.1)
				(type default)
			)
			(layer "F.Fab")
		)
		(fp_line
			(start 0.120396 0.3048)
			(end 0.120396 0.2794)
			(stroke
				(width 0.1)
				(type default)
			)
			(layer "F.Fab")
		)
		(fp_line
			(start 0.67945 0.3048)
			(end 0.120396 0.3048)
			(stroke
				(width 0.1)
				(type default)
			)
			(layer "F.Fab")
		)
		(fp_line
			(start -0.12065 0.2794)
			(end -0.12065 0.3048)
			(stroke
				(width 0.1)
				(type default)
			)
			(layer "F.Fab")
		)
		(fp_line
			(start 0.120396 0.2794)
			(end -0.12065 0.2794)
			(stroke
				(width 0.1)
				(type default)
			)
			(layer "F.Fab")
		)
		(fp_line
			(start -0.12065 -0.2794)
			(end 0.12065 -0.2794)
			(stroke
				(width 0.1)
				(type default)
			)
			(layer "F.Fab")
		)
		(fp_line
			(start 0.12065 -0.2794)
			(end 0.12065 -0.3048)
			(stroke
				(width 0.1)
				(type default)
			)
			(layer "F.Fab")
		)
		(fp_line
			(start 0.12065 -0.3048)
			(end 0.67945 -0.3048)
			(stroke
				(width 0.1)
				(type default)
			)
			(layer "F.Fab")
		)
		(fp_line
			(start 0.67945 -0.3048)
			(end 0.67945 0.3048)
			(stroke
				(width 0.1)
				(type default)
			)
			(layer "F.Fab")
		)
		(fp_line
			(start -0.67945 -0.305054)
			(end -0.12065 -0.305054)
			(stroke
				(width 0.1)
				(type default)
			)
			(layer "F.Fab")
		)
		(fp_line
			(start -0.12065 -0.305054)
			(end -0.12065 -0.2794)
			(stroke
				(width 0.1)
				(type default)
			)
			(layer "F.Fab")
		)
		(pad "1" smd circle
			(at -0.40005 0 270)
			(size 0 0)
			(layers "F.Cu" "F.Mask" "F.Paste")
			(net "MAX31790_U317_PWM_START1")
		)
		(pad "2" smd circle
			(at 0.40005 0 270)
			(size 0 0)
			(layers "F.Cu" "F.Mask" "F.Paste")
			(net "P3V3_AUX")
		)
	)
	(footprint ""
		(layer "F.Cu")
		(at 14.0589 -132.334 180)
		(property "Reference" "R5593"
			(at 0 0 180)
			(layer "F.SilkS")
			(hide yes)
			(effects
				(font
					(size 1.27 1.27)
				)
			)
		)
		(property "Value" ""
			(at 0 0 180)
			(layer "F.Fab")
			(effects
				(font
					(size 1.27 1.27)
				)
			)
		)
		(duplicate_pad_numbers_are_jumpers no)
		(fp_line
			(start 0.7874 0.4064)
			(end -0.7874 0.4064)
			(stroke
				(width 0.1524)
				(type default)
			)
			(layer "F.SilkS")
		)
		(fp_line
			(start 0.7874 -0.4064)
			(end 0.7874 0.4064)
			(stroke
				(width 0.1524)
				(type default)
			)
			(layer "F.SilkS")
		)
		(fp_line
			(start -0.7874 0.4064)
			(end -0.7874 -0.4064)
			(stroke
				(width 0.1524)
				(type default)
			)
			(layer "F.SilkS")
		)
		(fp_line
			(start -0.7874 -0.4064)
			(end 0.7874 -0.4064)
			(stroke
				(width 0.1524)
				(type default)
			)
			(layer "F.SilkS")
		)
		(fp_line
			(start 0.67945 0.3048)
			(end 0.120396 0.3048)
			(stroke
				(width 0.1)
				(type default)
			)
			(layer "F.Fab")
		)
		(fp_line
			(start 0.67945 -0.3048)
			(end 0.67945 0.3048)
			(stroke
				(width 0.1)
				(type default)
			)
			(layer "F.Fab")
		)
		(fp_line
			(start 0.12065 -0.2794)
			(end 0.12065 -0.3048)
			(stroke
				(width 0.1)
				(type default)
			)
			(layer "F.Fab")
		)
		(fp_line
			(start 0.12065 -0.3048)
			(end 0.67945 -0.3048)
			(stroke
				(width 0.1)
				(type default)
			)
			(layer "F.Fab")
		)
		(fp_line
			(start 0.120396 0.3048)
			(end 0.120396 0.2794)
			(stroke
				(width 0.1)
				(type default)
			)
			(layer "F.Fab")
		)
		(fp_line
			(start 0.120396 0.2794)
			(end -0.12065 0.2794)
			(stroke
				(width 0.1)
				(type default)
			)
			(layer "F.Fab")
		)
		(fp_line
			(start -0.12065 0.3048)
			(end -0.67945 0.3048)
			(stroke
				(width 0.1)
				(type default)
			)
			(layer "F.Fab")
		)
		(fp_line
			(start -0.12065 0.2794)
			(end -0.12065 0.3048)
			(stroke
				(width 0.1)
				(type default)
			)
			(layer "F.Fab")
		)
		(fp_line
			(start -0.12065 -0.2794)
			(end 0.12065 -0.2794)
			(stroke
				(width 0.1)
				(type default)
			)
			(layer "F.Fab")
		)
		(fp_line
			(start -0.12065 -0.305054)
			(end -0.12065 -0.2794)
			(stroke
				(width 0.1)
				(type default)
			)
			(layer "F.Fab")
		)
		(fp_line
			(start -0.67945 0.3048)
			(end -0.67945 -0.305054)
			(stroke
				(width 0.1)
				(type default)
			)
			(layer "F.Fab")
		)
		(fp_line
			(start -0.67945 -0.305054)
			(end -0.12065 -0.305054)
			(stroke
				(width 0.1)
				(type default)
			)
			(layer "F.Fab")
		)
		(pad "1" smd rect
			(at -0.40005 0)
			(size 0.4572 0.508)
			(layers "F.Cu" "F.Mask" "F.Paste")
			(net "FAN_7_TACH_IL")
		)
		(pad "2" smd rect
			(at 0.40005 0)
			(size 0.4572 0.508)
			(layers "F.Cu" "F.Mask" "F.Paste")
			(net "FAN_7_TACH_IL_R2")
		)
	)
	(footprint ""
		(layer "F.Cu")
		(at 44.667932 -71.304912 -90)
		(property "Reference" "C2068"
			(at 0 0 270)
			(layer "F.SilkS")
			(hide yes)
			(effects
				(font
					(size 1.27 1.27)
				)
			)
		)
		(property "Value" ""
			(at 0 0 270)
			(layer "F.Fab")
			(effects
				(font
					(size 1.27 1.27)
				)
			)
		)
		(duplicate_pad_numbers_are_jumpers no)
		(fp_line
			(start -0.7874 0.4064)
			(end -0.7874 -0.4064)
			(stroke
				(width 0.1524)
				(type default)
			)
			(layer "F.SilkS")
		)
		(fp_line
			(start 0.7874 0.4064)
			(end -0.7874 0.4064)
			(stroke
				(width 0.1524)
				(type default)
			)
			(layer "F.SilkS")
		)
		(fp_line
			(start -0.7874 -0.4064)
			(end 0.7874 -0.4064)
			(stroke
				(width 0.1524)
				(type default)
			)
			(layer "F.SilkS")
		)
		(fp_line
			(start 0.7874 -0.4064)
			(end 0.7874 0.4064)
			(stroke
				(width 0.1524)
				(type default)
			)
			(layer "F.SilkS")
		)
		(fp_line
			(start -0.67945 0.3048)
			(end -0.67945 -0.305054)
			(stroke
				(width 0.1)
				(type default)
			)
			(layer "F.Fab")
		)
		(fp_line
			(start -0.12065 0.3048)
			(end -0.67945 0.3048)
			(stroke
				(width 0.1)
				(type default)
			)
			(layer "F.Fab")
		)
		(fp_line
			(start 0.120396 0.3048)
			(end 0.120396 0.2794)
			(stroke
				(width 0.1)
				(type default)
			)
			(layer "F.Fab")
		)
		(fp_line
			(start 0.67945 0.3048)
			(end 0.120396 0.3048)
			(stroke
				(width 0.1)
				(type default)
			)
			(layer "F.Fab")
		)
		(fp_line
			(start -0.12065 0.2794)
			(end -0.12065 0.3048)
			(stroke
				(width 0.1)
				(type default)
			)
			(layer "F.Fab")
		)
		(fp_line
			(start 0.120396 0.2794)
			(end -0.12065 0.2794)
			(stroke
				(width 0.1)
				(type default)
			)
			(layer "F.Fab")
		)
		(fp_line
			(start -0.12065 -0.2794)
			(end 0.12065 -0.2794)
			(stroke
				(width 0.1)
				(type default)
			)
			(layer "F.Fab")
		)
		(fp_line
			(start 0.12065 -0.2794)
			(end 0.12065 -0.3048)
			(stroke
				(width 0.1)
				(type default)
			)
			(layer "F.Fab")
		)
		(fp_line
			(start 0.12065 -0.3048)
			(end 0.67945 -0.3048)
			(stroke
				(width 0.1)
				(type default)
			)
			(layer "F.Fab")
		)
		(fp_line
			(start 0.67945 -0.3048)
			(end 0.67945 0.3048)
			(stroke
				(width 0.1)
				(type default)
			)
			(layer "F.Fab")
		)
		(fp_line
			(start -0.67945 -0.305054)
			(end -0.12065 -0.305054)
			(stroke
				(width 0.1)
				(type default)
			)
			(layer "F.Fab")
		)
		(fp_line
			(start -0.12065 -0.305054)
			(end -0.12065 -0.2794)
			(stroke
				(width 0.1)
				(type default)
			)
			(layer "F.Fab")
		)
		(pad "1" smd circle
			(at -0.40005 0 270)
			(size 0 0)
			(layers "F.Cu" "F.Mask" "F.Paste")
			(net "P3V3_AUX")
		)
		(pad "2" smd circle
			(at 0.40005 0 270)
			(size 0 0)
			(layers "F.Cu" "F.Mask" "F.Paste")
			(net "GND")
		)
	)
	(footprint ""
		(layer "F.Cu")
		(at 37.846 -127.508 180)
		(property "Reference" "R5605"
			(at 0 0 180)
			(layer "F.SilkS")
			(hide yes)
			(effects
				(font
					(size 1.27 1.27)
				)
			)
		)
		(property "Value" ""
			(at 0 0 180)
			(layer "F.Fab")
			(effects
				(font
					(size 1.27 1.27)
				)
			)
		)
		(duplicate_pad_numbers_are_jumpers no)
		(fp_line
			(start 0.7874 0.4064)
			(end -0.7874 0.4064)
			(stroke
				(width 0.1524)
				(type default)
			)
			(layer "F.SilkS")
		)
		(fp_line
			(start 0.7874 -0.4064)
			(end 0.7874 0.4064)
			(stroke
				(width 0.1524)
				(type default)
			)
			(layer "F.SilkS")
		)
		(fp_line
			(start -0.7874 0.4064)
			(end -0.7874 -0.4064)
			(stroke
				(width 0.1524)
				(type default)
			)
			(layer "F.SilkS")
		)
		(fp_line
			(start -0.7874 -0.4064)
			(end 0.7874 -0.4064)
			(stroke
				(width 0.1524)
				(type default)
			)
			(layer "F.SilkS")
		)
		(fp_line
			(start 0.67945 0.3048)
			(end 0.120396 0.3048)
			(stroke
				(width 0.1)
				(type default)
			)
			(layer "F.Fab")
		)
		(fp_line
			(start 0.67945 -0.3048)
			(end 0.67945 0.3048)
			(stroke
				(width 0.1)
				(type default)
			)
			(layer "F.Fab")
		)
		(fp_line
			(start 0.12065 -0.2794)
			(end 0.12065 -0.3048)
			(stroke
				(width 0.1)
				(type default)
			)
			(layer "F.Fab")
		)
		(fp_line
			(start 0.12065 -0.3048)
			(end 0.67945 -0.3048)
			(stroke
				(width 0.1)
				(type default)
			)
			(layer "F.Fab")
		)
		(fp_line
			(start 0.120396 0.3048)
			(end 0.120396 0.2794)
			(stroke
				(width 0.1)
				(type default)
			)
			(layer "F.Fab")
		)
		(fp_line
			(start 0.120396 0.2794)
			(end -0.12065 0.2794)
			(stroke
				(width 0.1)
				(type default)
			)
			(layer "F.Fab")
		)
		(fp_line
			(start -0.12065 0.3048)
			(end -0.67945 0.3048)
			(stroke
				(width 0.1)
				(type default)
			)
			(layer "F.Fab")
		)
		(fp_line
			(start -0.12065 0.2794)
			(end -0.12065 0.3048)
			(stroke
				(width 0.1)
				(type default)
			)
			(layer "F.Fab")
		)
		(fp_line
			(start -0.12065 -0.2794)
			(end 0.12065 -0.2794)
			(stroke
				(width 0.1)
				(type default)
			)
			(layer "F.Fab")
		)
		(fp_line
			(start -0.12065 -0.305054)
			(end -0.12065 -0.2794)
			(stroke
				(width 0.1)
				(type default)
			)
			(layer "F.Fab")
		)
		(fp_line
			(start -0.67945 0.3048)
			(end -0.67945 -0.305054)
			(stroke
				(width 0.1)
				(type default)
			)
			(layer "F.Fab")
		)
		(fp_line
			(start -0.67945 -0.305054)
			(end -0.12065 -0.305054)
			(stroke
				(width 0.1)
				(type default)
			)
			(layer "F.Fab")
		)
		(pad "1" smd rect
			(at -0.40005 0)
			(size 0.4572 0.508)
			(layers "F.Cu" "F.Mask" "F.Paste")
			(net "FAN_3_TACH_IL")
		)
		(pad "2" smd rect
			(at 0.40005 0)
			(size 0.4572 0.508)
			(layers "F.Cu" "F.Mask" "F.Paste")
			(net "FAN_3_TACH_IL_R1")
		)
	)
	(footprint ""
		(layer "F.Cu")
		(at 32.258 -294.894 90)
		(property "Reference" "R5387"
			(at 0 0 90)
			(layer "F.SilkS")
			(hide yes)
			(effects
				(font
					(size 1.27 1.27)
				)
			)
		)
		(property "Value" ""
			(at 0 0 90)
			(layer "F.Fab")
			(effects
				(font
					(size 1.27 1.27)
				)
			)
		)
		(duplicate_pad_numbers_are_jumpers no)
		(fp_line
			(start 0.7874 -0.4064)
			(end 0.7874 0.4064)
			(stroke
				(width 0.1524)
				(type default)
			)
			(layer "F.SilkS")
		)
		(fp_line
			(start -0.7874 -0.4064)
			(end 0.7874 -0.4064)
			(stroke
				(width 0.1524)
				(type default)
			)
			(layer "F.SilkS")
		)
		(fp_line
			(start 0.7874 0.4064)
			(end -0.7874 0.4064)
			(stroke
				(width 0.1524)
				(type default)
			)
			(layer "F.SilkS")
		)
		(fp_line
			(start -0.7874 0.4064)
			(end -0.7874 -0.4064)
			(stroke
				(width 0.1524)
				(type default)
			)
			(layer "F.SilkS")
		)
		(fp_line
			(start -0.12065 -0.305054)
			(end -0.12065 -0.2794)
			(stroke
				(width 0.1)
				(type default)
			)
			(layer "F.Fab")
		)
		(fp_line
			(start -0.67945 -0.305054)
			(end -0.12065 -0.305054)
			(stroke
				(width 0.1)
				(type default)
			)
			(layer "F.Fab")
		)
		(fp_line
			(start 0.67945 -0.3048)
			(end 0.67945 0.3048)
			(stroke
				(width 0.1)
				(type default)
			)
			(layer "F.Fab")
		)
		(fp_line
			(start 0.12065 -0.3048)
			(end 0.67945 -0.3048)
			(stroke
				(width 0.1)
				(type default)
			)
			(layer "F.Fab")
		)
		(fp_line
			(start 0.12065 -0.2794)
			(end 0.12065 -0.3048)
			(stroke
				(width 0.1)
				(type default)
			)
			(layer "F.Fab")
		)
		(fp_line
			(start -0.12065 -0.2794)
			(end 0.12065 -0.2794)
			(stroke
				(width 0.1)
				(type default)
			)
			(layer "F.Fab")
		)
		(fp_line
			(start 0.120396 0.2794)
			(end -0.12065 0.2794)
			(stroke
				(width 0.1)
				(type default)
			)
			(layer "F.Fab")
		)
		(fp_line
			(start -0.12065 0.2794)
			(end -0.12065 0.3048)
			(stroke
				(width 0.1)
				(type default)
			)
			(layer "F.Fab")
		)
		(fp_line
			(start 0.67945 0.3048)
			(end 0.120396 0.3048)
			(stroke
				(width 0.1)
				(type default)
			)
			(layer "F.Fab")
		)
		(fp_line
			(start 0.120396 0.3048)
			(end 0.120396 0.2794)
			(stroke
				(width 0.1)
				(type default)
			)
			(layer "F.Fab")
		)
		(fp_line
			(start -0.12065 0.3048)
			(end -0.67945 0.3048)
			(stroke
				(width 0.1)
				(type default)
			)
			(layer "F.Fab")
		)
		(fp_line
			(start -0.67945 0.3048)
			(end -0.67945 -0.305054)
			(stroke
				(width 0.1)
				(type default)
			)
			(layer "F.Fab")
		)
		(pad "1" smd circle
			(at -0.40005 0 90)
			(size 0 0)
			(layers "F.Cu" "F.Mask" "F.Paste")
			(net "P3V3_AUX")
		)
		(pad "2" smd circle
			(at 0.40005 0 90)
			(size 0 0)
			(layers "F.Cu" "F.Mask" "F.Paste")
			(net "FAN_0_FAIL_R_LED")
		)
	)
	(footprint ""
		(layer "F.Cu")
		(at 14.234922 -286.6771 180)
		(property "Reference" "R5238"
			(at 0 0 180)
			(layer "F.SilkS")
			(hide yes)
			(effects
				(font
					(size 1.27 1.27)
				)
			)
		)
		(property "Value" ""
			(at 0 0 180)
			(layer "F.Fab")
			(effects
				(font
					(size 1.27 1.27)
				)
			)
		)
		(duplicate_pad_numbers_are_jumpers no)
		(fp_line
			(start 0.7874 0.4064)
			(end -0.7874 0.4064)
			(stroke
				(width 0.1524)
				(type default)
			)
			(layer "F.SilkS")
		)
		(fp_line
			(start 0.7874 -0.4064)
			(end 0.7874 0.4064)
			(stroke
				(width 0.1524)
				(type default)
			)
			(layer "F.SilkS")
		)
		(fp_line
			(start -0.7874 0.4064)
			(end -0.7874 -0.4064)
			(stroke
				(width 0.1524)
				(type default)
			)
			(layer "F.SilkS")
		)
		(fp_line
			(start -0.7874 -0.4064)
			(end 0.7874 -0.4064)
			(stroke
				(width 0.1524)
				(type default)
			)
			(layer "F.SilkS")
		)
		(fp_line
			(start 0.67945 0.3048)
			(end 0.120396 0.3048)
			(stroke
				(width 0.1)
				(type default)
			)
			(layer "F.Fab")
		)
		(fp_line
			(start 0.67945 -0.3048)
			(end 0.67945 0.3048)
			(stroke
				(width 0.1)
				(type default)
			)
			(layer "F.Fab")
		)
		(fp_line
			(start 0.12065 -0.2794)
			(end 0.12065 -0.3048)
			(stroke
				(width 0.1)
				(type default)
			)
			(layer "F.Fab")
		)
		(fp_line
			(start 0.12065 -0.3048)
			(end 0.67945 -0.3048)
			(stroke
				(width 0.1)
				(type default)
			)
			(layer "F.Fab")
		)
		(fp_line
			(start 0.120396 0.3048)
			(end 0.120396 0.2794)
			(stroke
				(width 0.1)
				(type default)
			)
			(layer "F.Fab")
		)
		(fp_line
			(start 0.120396 0.2794)
			(end -0.12065 0.2794)
			(stroke
				(width 0.1)
				(type default)
			)
			(layer "F.Fab")
		)
		(fp_line
			(start -0.12065 0.3048)
			(end -0.67945 0.3048)
			(stroke
				(width 0.1)
				(type default)
			)
			(layer "F.Fab")
		)
		(fp_line
			(start -0.12065 0.2794)
			(end -0.12065 0.3048)
			(stroke
				(width 0.1)
				(type default)
			)
			(layer "F.Fab")
		)
		(fp_line
			(start -0.12065 -0.2794)
			(end 0.12065 -0.2794)
			(stroke
				(width 0.1)
				(type default)
			)
			(layer "F.Fab")
		)
		(fp_line
			(start -0.12065 -0.305054)
			(end -0.12065 -0.2794)
			(stroke
				(width 0.1)
				(type default)
			)
			(layer "F.Fab")
		)
		(fp_line
			(start -0.67945 0.3048)
			(end -0.67945 -0.305054)
			(stroke
				(width 0.1)
				(type default)
			)
			(layer "F.Fab")
		)
		(fp_line
			(start -0.67945 -0.305054)
			(end -0.12065 -0.305054)
			(stroke
				(width 0.1)
				(type default)
			)
			(layer "F.Fab")
		)
		(pad "1" smd circle
			(at -0.40005 0 180)
			(size 0 0)
			(layers "F.Cu" "F.Mask" "F.Paste")
			(net "FAN_7_PWM_OL")
		)
		(pad "2" smd circle
			(at 0.40005 0 180)
			(size 0 0)
			(layers "F.Cu" "F.Mask" "F.Paste")
			(net "FAN_7_PWM_OL_R")
		)
	)
)
